(kicad_pcb
	(version 20260206)
	(generator "pcbnew")
	(generator_version "10.0")
	(general
		(thickness 1.6)
		(legacy_teardrops no)
	)
	(paper "A4")
	(title_block
		(title "Bryce Canyon_R.DPB_16317-1_OCP.brd")
		(comment 1 "Bryce Canyon / footprints 1570-1576 of 2099")
	)
	(layers
		(0 "F.Cu" signal "TOP")
		(4 "In1.Cu" signal "L2GND")
		(6 "In2.Cu" signal "L3")
		(8 "In3.Cu" signal "L4VCC")
		(10 "In4.Cu" signal "L5VCC")
		(12 "In5.Cu" signal "L6")
		(14 "In6.Cu" signal "L7GND")
		(2 "B.Cu" signal "BOTTOM")
		(9 "F.Adhes" user "F.Adhesive")
		(11 "B.Adhes" user "B.Adhesive")
		(13 "F.Paste" user "Package Geometry/Pastemask Top")
		(15 "B.Paste" user "Package Geometry/Pastemask Bottom")
		(5 "F.SilkS" user "Ref Des/Silkscreen Top")
		(7 "B.SilkS" user "Ref Des/Silkscreen Bottom")
		(1 "F.Mask" user "Board Geometry/Soldermask Top")
		(3 "B.Mask" user "Board Geometry/Soldermask Bottom")
		(17 "Dwgs.User" user "User.Drawings")
		(19 "Cmts.User" user "User.Comments")
		(21 "Eco1.User" user "User.Eco1")
		(23 "Eco2.User" user "User.Eco2")
		(25 "Edge.Cuts" user "Board Geometry/Outline")
		(27 "Margin" user)
		(31 "F.CrtYd" user "Package Geometry/Place Bound Top")
		(29 "B.CrtYd" user "Package Geometry/Place Bound Bottom")
		(35 "F.Fab" user "Ref Des/Assembly Top")
		(33 "B.Fab" user "Ref Des/Assembly Bottom")
	)
	(footprint ""
		(layer "F.Cu")
		(at 209.03946 -164.38626 -90)
		(property "Reference" "R60"
			(at 0 0 270)
			(layer "F.SilkS")
			(hide yes)
			(effects
				(font
					(size 1.27 1.27)
				)
			)
		)
		(property "Value" "0R2J-2-GP"
			(at 0.064008 -3.993896 270)
			(unlocked yes)
			(layer "F.Fab")
			(hide yes)
			(effects
				(font
					(size 1.016 1.016)
					(thickness 0.1524)
				)
			)
		)
		(property "Device Type" "R402H16"
			(at 0.064008 -5.517896 270)
			(unlocked yes)
			(layer "F.Fab")
			(hide yes)
			(effects
				(font
					(size 1.016 1.016)
					(thickness 0.1524)
				)
			)
		)
		(duplicate_pad_numbers_are_jumpers no)
		(fp_line
			(start -0.508 -0.9398)
			(end -0.508 0.9398)
			(stroke
				(width 0.1524)
				(type default)
			)
			(layer "F.SilkS")
		)
		(fp_line
			(start 0.508 -0.9398)
			(end -0.508 -0.9398)
			(stroke
				(width 0.1524)
				(type default)
			)
			(layer "F.SilkS")
		)
		(fp_rect
			(start -0.508 0.9398)
			(end 0.508 -0.9398)
			(stroke
				(width 0)
				(type default)
			)
			(fill no)
			(layer "F.CrtYd")
		)
		(fp_rect
			(start -0.508 0.9398)
			(end 0.508 -0.9398)
			(stroke
				(width 0)
				(type default)
			)
			(fill no)
			(layer "F.Fab")
		)
		(pad "1" smd custom
			(at 0 -0.4445 270)
			(size 0.1397 0.1397)
			(layers "F.Cu" "F.Mask" "F.Paste")
			(net "IO_EXP6_SDA")
			(options
				(clearance outline)
				(anchor circle)
			)
			(primitives
				(gr_poly
					(pts
						(arc
							(start -0.1778 -0.2794)
							(mid -0.249642 -0.249642)
							(end -0.2794 -0.1778)
						)
						(arc
							(start -0.2794 0.1778)
							(mid -0.249642 0.249642)
							(end -0.1778 0.2794)
						)
						(arc
							(start 0.1778 0.2794)
							(mid 0.249642 0.249642)
							(end 0.2794 0.1778)
						)
						(arc
							(start 0.2794 -0.1778)
							(mid 0.249642 -0.249642)
							(end 0.1778 -0.2794)
						)
					)
					(width 0)
					(fill yes)
				)
			)
		)
		(pad "2" smd custom
			(at 0 0.4445 270)
			(size 0.1397 0.1397)
			(layers "F.Cu" "F.Mask" "F.Paste")
			(net "I2C_DRIVE_B_INS_SDA")
			(options
				(clearance outline)
				(anchor circle)
			)
			(primitives
				(gr_poly
					(pts
						(arc
							(start -0.1778 -0.2794)
							(mid -0.249642 -0.249642)
							(end -0.2794 -0.1778)
						)
						(arc
							(start -0.2794 0.1778)
							(mid -0.249642 0.249642)
							(end -0.1778 0.2794)
						)
						(arc
							(start 0.1778 0.2794)
							(mid 0.249642 0.249642)
							(end 0.2794 0.1778)
						)
						(arc
							(start 0.2794 -0.1778)
							(mid 0.249642 -0.249642)
							(end 0.1778 -0.2794)
						)
					)
					(width 0)
					(fill yes)
				)
			)
		)
	)
	(footprint ""
		(layer "F.Cu")
		(at 17.670018 -99.782884 180)
		(property "Reference" "Q231"
			(at 0 0 180)
			(layer "F.SilkS")
			(hide yes)
			(effects
				(font
					(size 1.27 1.27)
				)
			)
		)
		(property "Value" "2N7002K-2-GP"
			(at 0.127 -8.9662 180)
			(unlocked yes)
			(layer "F.Fab")
			(hide yes)
			(effects
				(font
					(size 1.016 1.016)
					(thickness 0.1524)
				)
			)
		)
		(property "Device Type" "SOT23DGS2D4H44"
			(at 0.127 -10.4902 180)
			(unlocked yes)
			(layer "F.Fab")
			(hide yes)
			(effects
				(font
					(size 1.016 1.016)
					(thickness 0.1524)
				)
			)
		)
		(duplicate_pad_numbers_are_jumpers no)
		(fp_line
			(start 1.651 1.778)
			(end 1.651 -1.778)
			(stroke
				(width 0.1524)
				(type default)
			)
			(layer "F.SilkS")
		)
		(fp_line
			(start 1.651 -1.778)
			(end -1.651 -1.778)
			(stroke
				(width 0.1524)
				(type default)
			)
			(layer "F.SilkS")
		)
		(fp_line
			(start -1.651 1.778)
			(end 1.651 1.778)
			(stroke
				(width 0.1524)
				(type default)
			)
			(layer "F.SilkS")
		)
		(fp_line
			(start -1.651 -1.778)
			(end -1.651 1.778)
			(stroke
				(width 0.1524)
				(type default)
			)
			(layer "F.SilkS")
		)
		(fp_poly
			(pts
				(xy -1.778 1.8796) (xy -1.778 -1.8796) (xy 1.778 -1.8796) (xy 1.778 1.8796)
			)
			(stroke
				(width 0)
				(type default)
			)
			(fill no)
			(layer "F.CrtYd")
		)
		(fp_poly
			(pts
				(xy -1.778 1.8796) (xy -1.778 -1.8796) (xy 1.778 -1.8796) (xy 1.778 1.8796)
			)
			(stroke
				(width 0)
				(type default)
			)
			(fill no)
			(layer "F.Fab")
		)
		(pad "D" smd custom
			(at 0 -0.9525 180)
			(size 0.1905 0.1905)
			(layers "F.Cu" "F.Mask" "F.Paste")
			(net "FLT_HDD12_N")
			(options
				(clearance outline)
				(anchor circle)
			)
			(primitives
				(gr_poly
					(pts
						(arc
							(start -0.1778 0.5715)
							(mid -0.321484 0.511984)
							(end -0.381 0.3683)
						)
						(arc
							(start -0.381 -0.3683)
							(mid -0.321484 -0.511984)
							(end -0.1778 -0.5715)
						)
						(arc
							(start 0.1778 -0.5715)
							(mid 0.321484 -0.511984)
							(end 0.381 -0.3683)
						)
						(arc
							(start 0.381 0.3683)
							(mid 0.321484 0.511984)
							(end 0.1778 0.5715)
						)
					)
					(width 0)
					(fill yes)
				)
			)
		)
		(pad "G" smd custom
			(at -0.98425 0.9525 180)
			(size 0.1905 0.1905)
			(layers "F.Cu" "F.Mask" "F.Paste")
			(net "DRIVE_B_12_FLT_LED")
			(options
				(clearance outline)
				(anchor circle)
			)
			(primitives
				(gr_poly
					(pts
						(arc
							(start -0.1778 0.5715)
							(mid -0.321484 0.511984)
							(end -0.381 0.3683)
						)
						(arc
							(start -0.381 -0.3683)
							(mid -0.321484 -0.511984)
							(end -0.1778 -0.5715)
						)
						(arc
							(start 0.1778 -0.5715)
							(mid 0.321484 -0.511984)
							(end 0.381 -0.3683)
						)
						(arc
							(start 0.381 0.3683)
							(mid 0.321484 0.511984)
							(end 0.1778 0.5715)
						)
					)
					(width 0)
					(fill yes)
				)
			)
		)
		(pad "S" smd custom
			(at 0.98425 0.9525 180)
			(size 0.1905 0.1905)
			(layers "F.Cu" "F.Mask" "F.Paste")
			(net "GND")
			(options
				(clearance outline)
				(anchor circle)
			)
			(primitives
				(gr_poly
					(pts
						(arc
							(start -0.1778 0.5715)
							(mid -0.321484 0.511984)
							(end -0.381 0.3683)
						)
						(arc
							(start -0.381 -0.3683)
							(mid -0.321484 -0.511984)
							(end -0.1778 -0.5715)
						)
						(arc
							(start 0.1778 -0.5715)
							(mid 0.321484 -0.511984)
							(end 0.381 -0.3683)
						)
						(arc
							(start 0.381 0.3683)
							(mid 0.321484 0.511984)
							(end 0.1778 0.5715)
						)
					)
					(width 0)
					(fill yes)
				)
			)
		)
	)
	(footprint ""
		(layer "F.Cu")
		(at 447.834512 -130.21945 -90)
		(property "Reference" "C314"
			(at 0 0 270)
			(layer "F.SilkS")
			(hide yes)
			(effects
				(font
					(size 1.27 1.27)
				)
			)
		)
		(property "Value" "SCD01U16V1KX-GP"
			(at -2.8321 -1.7399 270)
			(unlocked yes)
			(layer "F.Fab")
			(hide yes)
			(effects
				(font
					(size 1.016 1.016)
					(thickness 0.1524)
				)
			)
		)
		(property "Device Type" "C0201H13"
			(at -2.8321 -3.2639 270)
			(unlocked yes)
			(layer "F.Fab")
			(hide yes)
			(effects
				(font
					(size 1.016 1.016)
					(thickness 0.1524)
				)
			)
		)
		(duplicate_pad_numbers_are_jumpers no)
		(fp_rect
			(start -0.2794 0.6477)
			(end 0.2794 -0.6477)
			(stroke
				(width 0)
				(type default)
			)
			(fill no)
			(layer "F.CrtYd")
		)
		(fp_rect
			(start -0.2794 0.6477)
			(end 0.2794 -0.6477)
			(stroke
				(width 0)
				(type default)
			)
			(fill no)
			(layer "F.Fab")
		)
		(pad "1" smd custom
			(at 0 -0.2794 270)
			(size 0.0762 0.0762)
			(layers "F.Cu" "F.Mask" "F.Paste")
			(net "SAS_HDD_RX_N22")
			(options
				(clearance outline)
				(anchor circle)
			)
			(primitives
				(gr_poly
					(pts
						(arc
							(start 0.1524 -0.127)
							(mid 0.137521 -0.162921)
							(end 0.1016 -0.1778)
						)
						(arc
							(start -0.1016 -0.1778)
							(mid -0.137521 -0.162921)
							(end -0.1524 -0.127)
						)
						(arc
							(start -0.1524 0.127)
							(mid -0.137521 0.162921)
							(end -0.1016 0.1778)
						)
						(arc
							(start 0.1016 0.1778)
							(mid 0.137521 0.162921)
							(end 0.1524 0.127)
						)
					)
					(width 0)
					(fill yes)
				)
			)
		)
		(pad "2" smd custom
			(at 0 0.2794 270)
			(size 0.0762 0.0762)
			(layers "F.Cu" "F.Mask" "F.Paste")
			(net "PHY_SCC_B_TO_DRV_B_22_DN")
			(options
				(clearance outline)
				(anchor circle)
			)
			(primitives
				(gr_poly
					(pts
						(arc
							(start 0.1524 -0.127)
							(mid 0.137521 -0.162921)
							(end 0.1016 -0.1778)
						)
						(arc
							(start -0.1016 -0.1778)
							(mid -0.137521 -0.162921)
							(end -0.1524 -0.127)
						)
						(arc
							(start -0.1524 0.127)
							(mid -0.137521 0.162921)
							(end -0.1016 0.1778)
						)
						(arc
							(start 0.1016 0.1778)
							(mid 0.137521 0.162921)
							(end 0.1524 0.127)
						)
					)
					(width 0)
					(fill yes)
				)
			)
		)
	)
	(footprint ""
		(layer "F.Cu")
		(at 333.248 -243.586 180)
		(property "Reference" "R260"
			(at 0 0 180)
			(layer "F.SilkS")
			(hide yes)
			(effects
				(font
					(size 1.27 1.27)
				)
			)
		)
		(property "Value" "1KR2F-3-GP"
			(at 0.064008 -3.993896 180)
			(unlocked yes)
			(layer "F.Fab")
			(hide yes)
			(effects
				(font
					(size 1.016 1.016)
					(thickness 0.1524)
				)
			)
		)
		(property "Device Type" "R402H16"
			(at 0.064008 -5.517896 180)
			(unlocked yes)
			(layer "F.Fab")
			(hide yes)
			(effects
				(font
					(size 1.016 1.016)
					(thickness 0.1524)
				)
			)
		)
		(duplicate_pad_numbers_are_jumpers no)
		(fp_line
			(start 0.508 -0.9398)
			(end -0.508 -0.9398)
			(stroke
				(width 0.1524)
				(type default)
			)
			(layer "F.SilkS")
		)
		(fp_line
			(start -0.508 -0.9398)
			(end -0.508 0.9398)
			(stroke
				(width 0.1524)
				(type default)
			)
			(layer "F.SilkS")
		)
		(fp_rect
			(start -0.508 0.9398)
			(end 0.508 -0.9398)
			(stroke
				(width 0)
				(type default)
			)
			(fill no)
			(layer "F.CrtYd")
		)
		(fp_rect
			(start -0.508 0.9398)
			(end 0.508 -0.9398)
			(stroke
				(width 0)
				(type default)
			)
			(fill no)
			(layer "F.Fab")
		)
		(pad "1" smd custom
			(at 0 -0.4445 180)
			(size 0.1397 0.1397)
			(layers "F.Cu" "F.Mask" "F.Paste")
			(net "P3V3_STBY_B")
			(options
				(clearance outline)
				(anchor circle)
			)
			(primitives
				(gr_poly
					(pts
						(arc
							(start -0.1778 -0.2794)
							(mid -0.249642 -0.249642)
							(end -0.2794 -0.1778)
						)
						(arc
							(start -0.2794 0.1778)
							(mid -0.249642 0.249642)
							(end -0.1778 0.2794)
						)
						(arc
							(start 0.1778 0.2794)
							(mid 0.249642 0.249642)
							(end 0.2794 0.1778)
						)
						(arc
							(start 0.2794 -0.1778)
							(mid 0.249642 -0.249642)
							(end 0.1778 -0.2794)
						)
					)
					(width 0)
					(fill yes)
				)
			)
		)
		(pad "2" smd custom
			(at 0 0.4445 180)
			(size 0.1397 0.1397)
			(layers "F.Cu" "F.Mask" "F.Paste")
			(net "SW_PWR_R_HDD6")
			(options
				(clearance outline)
				(anchor circle)
			)
			(primitives
				(gr_poly
					(pts
						(arc
							(start -0.1778 -0.2794)
							(mid -0.249642 -0.249642)
							(end -0.2794 -0.1778)
						)
						(arc
							(start -0.2794 0.1778)
							(mid -0.249642 0.249642)
							(end -0.1778 0.2794)
						)
						(arc
							(start 0.1778 0.2794)
							(mid 0.249642 0.249642)
							(end 0.2794 0.1778)
						)
						(arc
							(start 0.2794 -0.1778)
							(mid 0.249642 -0.249642)
							(end 0.1778 -0.2794)
						)
					)
					(width 0)
					(fill yes)
				)
			)
		)
	)
	(footprint ""
		(layer "F.Cu")
		(at 255.934972 -373.09171 180)
		(property "Reference" "C558"
			(at 0 0 180)
			(layer "F.SilkS")
			(hide yes)
			(effects
				(font
					(size 1.27 1.27)
				)
			)
		)
		(property "Value" "SC2D2U25V5KX-2-GP"
			(at -0.0762 -6.1214 180)
			(unlocked yes)
			(layer "F.Fab")
			(hide yes)
			(effects
				(font
					(size 1.016 1.016)
					(thickness 0.1524)
				)
			)
		)
		(property "Device Type" "C805H54"
			(at -0.0762 -8.1534 180)
			(unlocked yes)
			(layer "F.Fab")
			(hide yes)
			(effects
				(font
					(size 1.016 1.016)
					(thickness 0.1524)
				)
			)
		)
		(duplicate_pad_numbers_are_jumpers no)
		(fp_line
			(start 0.635 0)
			(end -0.635 0)
			(stroke
				(width 0.508)
				(type default)
			)
			(layer "F.SilkS")
		)
		(fp_rect
			(start -0.9652 1.778)
			(end 0.9652 -1.778)
			(stroke
				(width 0)
				(type default)
			)
			(fill no)
			(layer "F.CrtYd")
		)
		(fp_poly
			(pts
				(xy -0.9652 -1.778) (xy 0.9652 -1.778) (xy 0.9652 1.778) (xy -0.9652 1.778)
			)
			(stroke
				(width 0)
				(type default)
			)
			(fill no)
			(layer "F.Fab")
		)
		(pad "1" smd rect
			(at 0 -0.9652 180)
			(size 1.397 1.143)
			(layers "F.Cu" "F.Mask" "F.Paste")
			(net "P12V_B_PGOOD")
		)
		(pad "2" smd rect
			(at 0 0.9652 180)
			(size 1.397 1.143)
			(layers "F.Cu" "F.Mask" "F.Paste")
			(net "GND")
		)
	)
	(footprint ""
		(layer "F.Cu")
		(at 324.085712 -102.373684 -90)
		(property "Reference" "R466"
			(at 0 0 270)
			(layer "F.SilkS")
			(hide yes)
			(effects
				(font
					(size 1.27 1.27)
				)
			)
		)
		(property "Value" "4K7R2F-GP"
			(at 0.064008 -3.993896 270)
			(unlocked yes)
			(layer "F.Fab")
			(hide yes)
			(effects
				(font
					(size 1.016 1.016)
					(thickness 0.1524)
				)
			)
		)
		(property "Device Type" "R402H16"
			(at 0.064008 -5.517896 270)
			(unlocked yes)
			(layer "F.Fab")
			(hide yes)
			(effects
				(font
					(size 1.016 1.016)
					(thickness 0.1524)
				)
			)
		)
		(duplicate_pad_numbers_are_jumpers no)
		(fp_line
			(start -0.508 -0.9398)
			(end -0.508 0.9398)
			(stroke
				(width 0.1524)
				(type default)
			)
			(layer "F.SilkS")
		)
		(fp_line
			(start 0.508 -0.9398)
			(end -0.508 -0.9398)
			(stroke
				(width 0.1524)
				(type default)
			)
			(layer "F.SilkS")
		)
		(fp_rect
			(start -0.508 0.9398)
			(end 0.508 -0.9398)
			(stroke
				(width 0)
				(type default)
			)
			(fill no)
			(layer "F.CrtYd")
		)
		(fp_rect
			(start -0.508 0.9398)
			(end 0.508 -0.9398)
			(stroke
				(width 0)
				(type default)
			)
			(fill no)
			(layer "F.Fab")
		)
		(pad "1" smd custom
			(at 0 -0.4445 270)
			(size 0.1397 0.1397)
			(layers "F.Cu" "F.Mask" "F.Paste")
			(net "DRIVE_B_18_FLT_LED")
			(options
				(clearance outline)
				(anchor circle)
			)
			(primitives
				(gr_poly
					(pts
						(arc
							(start -0.1778 -0.2794)
							(mid -0.249642 -0.249642)
							(end -0.2794 -0.1778)
						)
						(arc
							(start -0.2794 0.1778)
							(mid -0.249642 0.249642)
							(end -0.1778 0.2794)
						)
						(arc
							(start 0.1778 0.2794)
							(mid 0.249642 0.249642)
							(end 0.2794 0.1778)
						)
						(arc
							(start 0.2794 -0.1778)
							(mid 0.249642 -0.249642)
							(end 0.1778 -0.2794)
						)
					)
					(width 0)
					(fill yes)
				)
			)
		)
		(pad "2" smd custom
			(at 0 0.4445 270)
			(size 0.1397 0.1397)
			(layers "F.Cu" "F.Mask" "F.Paste")
			(net "GND")
			(options
				(clearance outline)
				(anchor circle)
			)
			(primitives
				(gr_poly
					(pts
						(arc
							(start -0.1778 -0.2794)
							(mid -0.249642 -0.249642)
							(end -0.2794 -0.1778)
						)
						(arc
							(start -0.2794 0.1778)
							(mid -0.249642 0.249642)
							(end -0.1778 0.2794)
						)
						(arc
							(start 0.1778 0.2794)
							(mid 0.249642 0.249642)
							(end 0.2794 0.1778)
						)
						(arc
							(start 0.2794 -0.1778)
							(mid 0.249642 -0.249642)
							(end 0.1778 -0.2794)
						)
					)
					(width 0)
					(fill yes)
				)
			)
		)
	)
	(footprint ""
		(layer "F.Cu")
		(at 86.868 -33.274)
		(property "Reference" "R667"
			(at 0 0 0)
			(layer "F.SilkS")
			(hide yes)
			(effects
				(font
					(size 1.27 1.27)
				)
			)
		)
		(property "Value" "2R6F-GP"
			(at -0.0508 -4.8514 0)
			(unlocked yes)
			(layer "F.Fab")
			(hide yes)
			(effects
				(font
					(size 1.016 1.016)
					(thickness 0.1524)
				)
			)
		)
		(property "Device Type" "R1206H26"
			(at 0 -6.3754 0)
			(unlocked yes)
			(layer "F.Fab")
			(hide yes)
			(effects
				(font
					(size 1.016 1.016)
					(thickness 0.1524)
				)
			)
		)
		(duplicate_pad_numbers_are_jumpers no)
		(fp_line
			(start -1.016 -2.2352)
			(end 1.016 -2.2352)
			(stroke
				(width 0.1524)
				(type default)
			)
			(layer "F.SilkS")
		)
		(fp_line
			(start -1.016 2.2352)
			(end -1.016 -2.2352)
			(stroke
				(width 0.1524)
				(type default)
			)
			(layer "F.SilkS")
		)
		(fp_line
			(start 1.016 -2.2352)
			(end 1.016 2.2352)
			(stroke
				(width 0.1524)
				(type default)
			)
			(layer "F.SilkS")
		)
		(fp_line
			(start 1.016 2.2352)
			(end -1.016 2.2352)
			(stroke
				(width 0.1524)
				(type default)
			)
			(layer "F.SilkS")
		)
		(fp_rect
			(start -1.0922 2.3114)
			(end 1.0922 -2.3114)
			(stroke
				(width 0)
				(type default)
			)
			(fill no)
			(layer "F.CrtYd")
		)
		(fp_poly
			(pts
				(xy -1.0922 -2.3114) (xy 1.0922 -2.3114) (xy 1.0922 2.3114) (xy -1.0922 2.3114)
			)
			(stroke
				(width 0)
				(type default)
			)
			(fill no)
			(layer "F.Fab")
		)
		(pad "1" smd rect
			(at 0 -1.397)
			(size 1.651 1.27)
			(layers "F.Cu" "F.Mask" "F.Paste")
			(net "P5V_HDD26")
		)
		(pad "2" smd rect
			(at 0 1.397)
			(size 1.651 1.27)
			(layers "F.Cu" "F.Mask" "F.Paste")
			(net "5V_PRE_26")
		)
	)
)
